(kicad_pcb
	(version 20240108)
	(generator "pcbnew")
	(generator_version "8.0")
	(general
		(thickness 1.586)
		(legacy_teardrops no)
	)
	(paper "A4")
	(title_block
		(title "GMSL Serializer")
		(date "2024-11-27")
		(rev "1.1.1")
		(company "Antmicro Ltd")
		(comment 1 "www.antmicro.com")
		(comment 9 "footprints 34-38 of 117")
	)
	(layers
		(0 "F.Cu" signal)
		(1 "In1.Cu" power)
		(2 "In2.Cu" power)
		(31 "B.Cu" signal)
		(32 "B.Adhes" user "B.Adhesive")
		(33 "F.Adhes" user "F.Adhesive")
		(34 "B.Paste" user)
		(35 "F.Paste" user)
		(36 "B.SilkS" user "B.Silkscreen")
		(37 "F.SilkS" user "F.Silkscreen")
		(38 "B.Mask" user)
		(39 "F.Mask" user)
		(40 "Dwgs.User" user "User.Drawings")
		(41 "Cmts.User" user "User.Comments")
		(42 "Eco1.User" user "User.Eco1")
		(43 "Eco2.User" user "User.Eco2")
		(44 "Edge.Cuts" user)
		(45 "Margin" user)
		(46 "B.CrtYd" user "B.Courtyard")
		(47 "F.CrtYd" user "F.Courtyard")
		(48 "B.Fab" user)
		(49 "F.Fab" user)
	)
	(footprint "antmicro-footprints:C_0402_1005Metric"
		(layer "F.Cu")
		(at 165.425 103.2 -90)
		(descr "Capacitor SMD 0402")
		(tags "capacitor SMD 0402")
		(property "Reference" "C8"
			(at 0.67 -0.49 90)
			(layer "F.SilkS")
			(effects
				(font
					(size 0.7 0.7)
					(thickness 0.15)
				)
				(justify right bottom)
			)
		)
		(property "Value" "C_22u_0402"
			(at -1.022927 2.155213 90)
			(layer "F.Fab")
			(effects
				(font
					(size 0.7 0.7)
					(thickness 0.15)
				)
				(justify right bottom)
			)
		)
		(property "Footprint" "antmicro-footprints:C_0402_1005Metric"
			(at 0 0 -90)
			(layer "F.Fab")
			(hide yes)
			(effects
				(font
					(size 1.27 1.27)
					(thickness 0.15)
				)
			)
		)
		(property "Datasheet" "https://www.murata.com/products/productdetail?partno=GRM158R60J226ME01%23"
			(at 0 0 -90)
			(layer "F.Fab")
			(hide yes)
			(effects
				(font
					(size 1.27 1.27)
					(thickness 0.15)
				)
			)
		)
		(property "Author" "Antmicro"
			(at 62.225 268.625 0)
			(layer "F.Fab")
			(hide yes)
			(effects
				(font
					(size 1 1)
					(thickness 0.15)
				)
			)
		)
		(property "Dielectric" ""
			(at 62.225 268.625 0)
			(layer "F.Fab")
			(hide yes)
			(effects
				(font
					(size 1 1)
					(thickness 0.15)
				)
			)
		)
		(property "License" "Apache-2.0"
			(at 62.225 268.625 0)
			(layer "F.Fab")
			(hide yes)
			(effects
				(font
					(size 1 1)
					(thickness 0.15)
				)
			)
		)
		(property "MPN" "GRM158R60J226ME01D"
			(at 62.225 268.625 0)
			(layer "F.Fab")
			(hide yes)
			(effects
				(font
					(size 1 1)
					(thickness 0.15)
				)
			)
		)
		(property "Manufacturer" "Murata"
			(at 62.225 268.625 0)
			(layer "F.Fab")
			(hide yes)
			(effects
				(font
					(size 1 1)
					(thickness 0.15)
				)
			)
		)
		(property "Val" "22u"
			(at 62.225 268.625 0)
			(layer "F.Fab")
			(hide yes)
			(effects
				(font
					(size 1 1)
					(thickness 0.15)
				)
			)
		)
		(property "Voltage" ""
			(at 62.225 268.625 0)
			(layer "F.Fab")
			(hide yes)
			(effects
				(font
					(size 1 1)
					(thickness 0.15)
				)
			)
		)
		(sheetname "Supply")
		(sheetfile "supply.kicad_sch")
		(attr smd)
		(fp_rect
			(start -0.925 -0.47)
			(end 0.925 0.47)
			(stroke
				(width 0.05)
				(type default)
			)
			(fill none)
			(layer "F.CrtYd")
		)
		(fp_line
			(start -0.494 0.248)
			(end -0.494 -0.25)
			(stroke
				(width 0.15)
				(type solid)
			)
			(layer "F.Fab")
		)
		(fp_line
			(start 0.504 0.248)
			(end -0.494 0.248)
			(stroke
				(width 0.15)
				(type solid)
			)
			(layer "F.Fab")
		)
		(fp_line
			(start -0.494 -0.25)
			(end 0.504 -0.25)
			(stroke
				(width 0.15)
				(type solid)
			)
			(layer "F.Fab")
		)
		(fp_line
			(start 0.504 -0.25)
			(end 0.504 0.248)
			(stroke
				(width 0.15)
				(type solid)
			)
			(layer "F.Fab")
		)
		(fp_text user "License: Apache-2.0"
			(at -0.939 5.799 90)
			(layer "F.Fab")
			(hide yes)
			(effects
				(font
					(size 0.7 0.7)
					(thickness 0.15)
				)
				(justify right bottom)
			)
		)
		(fp_text user "${REFERENCE}"
			(at -0.939 4.599 90)
			(layer "F.Fab")
			(hide yes)
			(effects
				(font
					(size 0.7 0.7)
					(thickness 0.15)
				)
				(justify right bottom)
			)
		)
		(fp_text user "Author: Antmicro"
			(at -0.939 3.399 90)
			(layer "F.Fab")
			(hide yes)
			(effects
				(font
					(size 0.7 0.7)
					(thickness 0.15)
				)
				(justify right bottom)
			)
		)
		(pad "1" smd roundrect
			(at -0.48 0 270)
			(size 0.59 0.64)
			(layers "F.Cu" "F.Paste" "F.Mask")
			(roundrect_rratio 0.25)
			(net 1 "GND")
			(pintype "passive")
		)
		(pad "2" smd roundrect
			(at 0.48 0 270)
			(size 0.59 0.64)
			(layers "F.Cu" "F.Paste" "F.Mask")
			(roundrect_rratio 0.25)
			(net 8 "/Supply/OUT_1V8")
			(pintype "passive")
		)
	)
	(footprint "antmicro-footprints:R_0402_1005Metric"
		(layer "F.Cu")
		(at 158.267 96.878 180)
		(descr "Resistor SMD 0402")
		(tags "resistor SMD 0402")
		(property "Reference" "R17"
			(at 0.882 -0.352 0)
			(layer "F.SilkS")
			(effects
				(font
					(size 0.7 0.7)
					(thickness 0.15)
				)
				(justify right bottom)
			)
		)
		(property "Value" "R_5k1_0402"
			(at -1.011843 1.772047 0)
			(layer "F.Fab")
			(effects
				(font
					(size 0.7 0.7)
					(thickness 0.15)
				)
				(justify right bottom)
			)
		)
		(property "Footprint" "antmicro-footprints:R_0402_1005Metric"
			(at 0 0 180)
			(layer "F.Fab")
			(hide yes)
			(effects
				(font
					(size 1.27 1.27)
					(thickness 0.15)
				)
			)
		)
		(property "Datasheet" "https://www.bourns.com/docs/product-datasheets/cr.pdf"
			(at 0 0 180)
			(layer "F.Fab")
			(hide yes)
			(effects
				(font
					(size 1.27 1.27)
					(thickness 0.15)
				)
			)
		)
		(property "Author" "Antmicro"
			(at 316.534 193.756 0)
			(layer "F.Fab")
			(hide yes)
			(effects
				(font
					(size 1 1)
					(thickness 0.15)
				)
			)
		)
		(property "License" "Apache-2.0"
			(at 316.534 193.756 0)
			(layer "F.Fab")
			(hide yes)
			(effects
				(font
					(size 1 1)
					(thickness 0.15)
				)
			)
		)
		(property "MPN" "CR0402-FX-5101GLF"
			(at 316.534 193.756 0)
			(layer "F.Fab")
			(hide yes)
			(effects
				(font
					(size 1 1)
					(thickness 0.15)
				)
			)
		)
		(property "Manufacturer" "Bourns"
			(at 316.534 193.756 0)
			(layer "F.Fab")
			(hide yes)
			(effects
				(font
					(size 1 1)
					(thickness 0.15)
				)
			)
		)
		(property "Tolerance" "1%"
			(at 316.534 193.756 0)
			(layer "F.Fab")
			(hide yes)
			(effects
				(font
					(size 1 1)
					(thickness 0.15)
				)
			)
		)
		(property "Val" "5k1"
			(at 316.534 193.756 0)
			(layer "F.Fab")
			(hide yes)
			(effects
				(font
					(size 1 1)
					(thickness 0.15)
				)
			)
		)
		(sheetname "GMSL Connector")
		(sheetfile "GMSL.kicad_sch")
		(attr smd)
		(fp_rect
			(start -0.925 -0.47)
			(end 0.925 0.47)
			(stroke
				(width 0.05)
				(type default)
			)
			(fill none)
			(layer "F.CrtYd")
		)
		(fp_rect
			(start -0.5 -0.25)
			(end 0.5 0.25)
			(stroke
				(width 0.15)
				(type solid)
			)
			(fill none)
			(layer "F.Fab")
		)
		(fp_text user "License: Apache-2.0"
			(at -0.95 5.169 0)
			(layer "F.Fab")
			(hide yes)
			(effects
				(font
					(size 0.7 0.7)
					(thickness 0.15)
				)
				(justify right bottom)
			)
		)
		(fp_text user "${REFERENCE}"
			(at -0.95 3.168 0)
			(layer "F.Fab")
			(hide yes)
			(effects
				(font
					(size 0.7 0.7)
					(thickness 0.15)
				)
				(justify right bottom)
			)
		)
		(fp_text user "Author: Antmicro"
			(at -0.95 4.169 0)
			(layer "F.Fab")
			(hide yes)
			(effects
				(font
					(size 0.7 0.7)
					(thickness 0.15)
				)
				(justify right bottom)
			)
		)
		(pad "1" smd roundrect
			(at -0.48 0 180)
			(size 0.59 0.64)
			(layers "F.Cu" "F.Paste" "F.Mask")
			(roundrect_rratio 0.25)
			(net 58 "Net-(L3-Pad2)")
			(pintype "passive")
		)
		(pad "2" smd roundrect
			(at 0.48 0 180)
			(size 0.59 0.64)
			(layers "F.Cu" "F.Paste" "F.Mask")
			(roundrect_rratio 0.25)
			(net 59 "Net-(L4-Pad2)")
			(pintype "passive")
		)
	)
	(footprint "antmicro-footprints:C_0603_1608Metric"
		(layer "F.Cu")
		(at 164.775 100.625 90)
		(descr "Capacitor SMD 0603")
		(tags "capacitor 0603")
		(property "Reference" "C2"
			(at -0.7 1.5 90)
			(layer "F.SilkS")
			(effects
				(font
					(size 0.7 0.7)
					(thickness 0.15)
				)
				(justify left bottom)
			)
		)
		(property "Value" "C_10u_25V_0603"
			(at -1.42757 1.770288 90)
			(layer "F.Fab")
			(effects
				(font
					(size 0.7 0.7)
					(thickness 0.15)
				)
				(justify left bottom)
			)
		)
		(property "Footprint" "antmicro-footprints:C_0603_1608Metric"
			(at 0 0 90)
			(layer "F.Fab")
			(hide yes)
			(effects
				(font
					(size 1.27 1.27)
					(thickness 0.15)
				)
			)
		)
		(property "Datasheet" "https://product.tdk.com/en/search/capacitor/ceramic/mlcc/info?part_no=C1608X5R1E106M080AC"
			(at 0 0 90)
			(layer "F.Fab")
			(hide yes)
			(effects
				(font
					(size 1.27 1.27)
					(thickness 0.15)
				)
			)
		)
		(property "Author" "Antmicro"
			(at 265.4 -64.15 0)
			(layer "F.Fab")
			(hide yes)
			(effects
				(font
					(size 1 1)
					(thickness 0.15)
				)
			)
		)
		(property "Dielectric" ""
			(at 265.4 -64.15 0)
			(layer "F.Fab")
			(hide yes)
			(effects
				(font
					(size 1 1)
					(thickness 0.15)
				)
			)
		)
		(property "License" "Apache-2.0"
			(at 265.4 -64.15 0)
			(layer "F.Fab")
			(hide yes)
			(effects
				(font
					(size 1 1)
					(thickness 0.15)
				)
			)
		)
		(property "MPN" "C1608X5R1E106M080AC"
			(at 265.4 -64.15 0)
			(layer "F.Fab")
			(hide yes)
			(effects
				(font
					(size 1 1)
					(thickness 0.15)
				)
			)
		)
		(property "Manufacturer" "TDK"
			(at 265.4 -64.15 0)
			(layer "F.Fab")
			(hide yes)
			(effects
				(font
					(size 1 1)
					(thickness 0.15)
				)
			)
		)
		(property "Val" "10u"
			(at 265.4 -64.15 0)
			(layer "F.Fab")
			(hide yes)
			(effects
				(font
					(size 1 1)
					(thickness 0.15)
				)
			)
		)
		(property "Voltage" "25V"
			(at 265.4 -64.15 0)
			(layer "F.Fab")
			(hide yes)
			(effects
				(font
					(size 1 1)
					(thickness 0.15)
				)
			)
		)
		(sheetname "Supply")
		(sheetfile "supply.kicad_sch")
		(attr smd)
		(fp_line
			(start -0.15 -0.4)
			(end 0.15 -0.4)
			(stroke
				(width 0.15)
				(type solid)
			)
			(layer "F.SilkS")
		)
		(fp_line
			(start -0.15 0.4)
			(end 0.15 0.4)
			(stroke
				(width 0.15)
				(type solid)
			)
			(layer "F.SilkS")
		)
		(fp_rect
			(start -1.25 -0.65)
			(end 1.25 0.65)
			(stroke
				(width 0.05)
				(type solid)
			)
			(fill none)
			(layer "F.CrtYd")
		)
		(fp_rect
			(start -0.8 -0.4)
			(end 0.8 0.4)
			(stroke
				(width 0.15)
				(type solid)
			)
			(fill none)
			(layer "F.Fab")
		)
		(fp_text user "Author: Antmicro"
			(at -1.682 4.894 90)
			(layer "F.Fab")
			(hide yes)
			(effects
				(font
					(size 0.7 0.7)
					(thickness 0.15)
				)
				(justify left bottom)
			)
		)
		(fp_text user "License: Apache-2.0"
			(at -1.682 5.895 90)
			(layer "F.Fab")
			(hide yes)
			(effects
				(font
					(size 0.7 0.7)
					(thickness 0.15)
				)
				(justify left bottom)
			)
		)
		(fp_text user "${REFERENCE}"
			(at -1.682 3.895 90)
			(layer "F.Fab")
			(hide yes)
			(effects
				(font
					(size 0.7 0.7)
					(thickness 0.15)
				)
				(justify left bottom)
			)
		)
		(pad "1" smd roundrect
			(at -0.7 0 90)
			(size 0.8 1)
			(layers "F.Cu" "F.Paste" "F.Mask")
			(roundrect_rratio 0.2)
			(net 1 "GND")
			(pintype "passive")
		)
		(pad "2" smd roundrect
			(at 0.7 0 90)
			(size 0.8 1)
			(layers "F.Cu" "F.Paste" "F.Mask")
			(roundrect_rratio 0.2)
			(net 2 "+12V")
			(pintype "passive")
		)
	)
	(footprint "antmicro-footprints:C_0402_1005Metric"
		(layer "F.Cu")
		(at 146.15 85.75 -90)
		(descr "Capacitor SMD 0402")
		(tags "capacitor SMD 0402")
		(property "Reference" "C34"
			(at 0.85 -0.95 90)
			(layer "F.SilkS")
			(effects
				(font
					(size 0.7 0.7)
					(thickness 0.15)
				)
				(justify right top)
			)
		)
		(property "Value" "C_22u_0402"
			(at -1.022927 2.155213 90)
			(layer "F.Fab")
			(effects
				(font
					(size 0.7 0.7)
					(thickness 0.15)
				)
				(justify right top)
			)
		)
		(property "Footprint" "antmicro-footprints:C_0402_1005Metric"
			(at 0 0 90)
			(layer "F.Fab")
			(hide yes)
			(effects
				(font
					(size 1.27 1.27)
					(thickness 0.15)
				)
			)
		)
		(property "Datasheet" "https://www.murata.com/products/productdetail?partno=GRM158R60J226ME01%23"
			(at 0 0 90)
			(layer "F.Fab")
			(hide yes)
			(effects
				(font
					(size 1.27 1.27)
					(thickness 0.15)
				)
			)
		)
		(property "MPN" "GRM158R60J226ME01D"
			(at 0 0 -90)
			(unlocked yes)
			(layer "F.Fab")
			(hide yes)
			(effects
				(font
					(size 1 1)
					(thickness 0.15)
				)
			)
		)
		(property "Manufacturer" "Murata"
			(at 0 0 -90)
			(unlocked yes)
			(layer "F.Fab")
			(hide yes)
			(effects
				(font
					(size 1 1)
					(thickness 0.15)
				)
			)
		)
		(property "License" "Apache-2.0"
			(at 0 0 -90)
			(unlocked yes)
			(layer "F.Fab")
			(hide yes)
			(effects
				(font
					(size 1 1)
					(thickness 0.15)
				)
			)
		)
		(property "Author" "Antmicro"
			(at 0 0 -90)
			(unlocked yes)
			(layer "F.Fab")
			(hide yes)
			(effects
				(font
					(size 1 1)
					(thickness 0.15)
				)
			)
		)
		(property "Val" "22u"
			(at 0 0 -90)
			(unlocked yes)
			(layer "F.Fab")
			(hide yes)
			(effects
				(font
					(size 1 1)
					(thickness 0.15)
				)
			)
		)
		(property "Voltage" ""
			(at 0 0 -90)
			(unlocked yes)
			(layer "F.Fab")
			(hide yes)
			(effects
				(font
					(size 1 1)
					(thickness 0.15)
				)
			)
		)
		(property "Dielectric" ""
			(at 0 0 -90)
			(unlocked yes)
			(layer "F.Fab")
			(hide yes)
			(effects
				(font
					(size 1 1)
					(thickness 0.15)
				)
			)
		)
		(sheetname "Supply")
		(sheetfile "supply.kicad_sch")
		(attr smd)
		(fp_rect
			(start -0.925 -0.47)
			(end 0.925 0.47)
			(stroke
				(width 0.05)
				(type default)
			)
			(fill none)
			(layer "F.CrtYd")
		)
		(fp_line
			(start -0.494 0.248)
			(end -0.494 -0.25)
			(stroke
				(width 0.15)
				(type solid)
			)
			(layer "F.Fab")
		)
		(fp_line
			(start 0.504 0.248)
			(end -0.494 0.248)
			(stroke
				(width 0.15)
				(type solid)
			)
			(layer "F.Fab")
		)
		(fp_line
			(start -0.494 -0.25)
			(end 0.504 -0.25)
			(stroke
				(width 0.15)
				(type solid)
			)
			(layer "F.Fab")
		)
		(fp_line
			(start 0.504 -0.25)
			(end 0.504 0.248)
			(stroke
				(width 0.15)
				(type solid)
			)
			(layer "F.Fab")
		)
		(fp_text user "Author: Antmicro"
			(at -0.939 3.399 90)
			(layer "F.Fab")
			(hide yes)
			(effects
				(font
					(size 0.7 0.7)
					(thickness 0.15)
				)
				(justify right top)
			)
		)
		(fp_text user "License: Apache-2.0"
			(at -0.939 5.799 90)
			(layer "F.Fab")
			(hide yes)
			(effects
				(font
					(size 0.7 0.7)
					(thickness 0.15)
				)
				(justify right top)
			)
		)
		(fp_text user "${REFERENCE}"
			(at -0.939 4.599 90)
			(layer "F.Fab")
			(hide yes)
			(effects
				(font
					(size 0.7 0.7)
					(thickness 0.15)
				)
				(justify right top)
			)
		)
		(pad "1" smd roundrect
			(at -0.48 0 270)
			(size 0.59 0.64)
			(layers "F.Cu" "F.Paste" "F.Mask")
			(roundrect_rratio 0.25)
			(net 1 "GND")
			(pintype "passive")
		)
		(pad "2" smd roundrect
			(at 0.48 0 270)
			(size 0.59 0.64)
			(layers "F.Cu" "F.Paste" "F.Mask")
			(roundrect_rratio 0.25)
			(net 94 "/Supply/OUT_3V3")
			(pintype "passive")
		)
	)
	(footprint "antmicro-footprints:C_0402_1005Metric"
		(layer "F.Cu")
		(at 164.475 103.2 -90)
		(descr "Capacitor SMD 0402")
		(tags "capacitor SMD 0402")
		(property "Reference" "C6"
			(at 0.51 0.3 90)
			(layer "F.SilkS")
			(effects
				(font
					(size 0.7 0.7)
					(thickness 0.15)
				)
				(justify right bottom)
			)
		)
		(property "Value" "C_22u_0402"
			(at -1.022927 2.155213 90)
			(layer "F.Fab")
			(effects
				(font
					(size 0.7 0.7)
					(thickness 0.15)
				)
				(justify right bottom)
			)
		)
		(property "Footprint" "antmicro-footprints:C_0402_1005Metric"
			(at 0 0 -90)
			(layer "F.Fab")
			(hide yes)
			(effects
				(font
					(size 1.27 1.27)
					(thickness 0.15)
				)
			)
		)
		(property "Datasheet" "https://www.murata.com/products/productdetail?partno=GRM158R60J226ME01%23"
			(at 0 0 -90)
			(layer "F.Fab")
			(hide yes)
			(effects
				(font
					(size 1.27 1.27)
					(thickness 0.15)
				)
			)
		)
		(property "Author" "Antmicro"
			(at 61.275 267.675 0)
			(layer "F.Fab")
			(hide yes)
			(effects
				(font
					(size 1 1)
					(thickness 0.15)
				)
			)
		)
		(property "Dielectric" ""
			(at 61.275 267.675 0)
			(layer "F.Fab")
			(hide yes)
			(effects
				(font
					(size 1 1)
					(thickness 0.15)
				)
			)
		)
		(property "License" "Apache-2.0"
			(at 61.275 267.675 0)
			(layer "F.Fab")
			(hide yes)
			(effects
				(font
					(size 1 1)
					(thickness 0.15)
				)
			)
		)
		(property "MPN" "GRM158R60J226ME01D"
			(at 61.275 267.675 0)
			(layer "F.Fab")
			(hide yes)
			(effects
				(font
					(size 1 1)
					(thickness 0.15)
				)
			)
		)
		(property "Manufacturer" "Murata"
			(at 61.275 267.675 0)
			(layer "F.Fab")
			(hide yes)
			(effects
				(font
					(size 1 1)
					(thickness 0.15)
				)
			)
		)
		(property "Val" "22u"
			(at 61.275 267.675 0)
			(layer "F.Fab")
			(hide yes)
			(effects
				(font
					(size 1 1)
					(thickness 0.15)
				)
			)
		)
		(property "Voltage" ""
			(at 61.275 267.675 0)
			(layer "F.Fab")
			(hide yes)
			(effects
				(font
					(size 1 1)
					(thickness 0.15)
				)
			)
		)
		(sheetname "Supply")
		(sheetfile "supply.kicad_sch")
		(attr smd)
		(fp_rect
			(start -0.925 -0.47)
			(end 0.925 0.47)
			(stroke
				(width 0.05)
				(type default)
			)
			(fill none)
			(layer "F.CrtYd")
		)
		(fp_line
			(start -0.494 0.248)
			(end -0.494 -0.25)
			(stroke
				(width 0.15)
				(type solid)
			)
			(layer "F.Fab")
		)
		(fp_line
			(start 0.504 0.248)
			(end -0.494 0.248)
			(stroke
				(width 0.15)
				(type solid)
			)
			(layer "F.Fab")
		)
		(fp_line
			(start -0.494 -0.25)
			(end 0.504 -0.25)
			(stroke
				(width 0.15)
				(type solid)
			)
			(layer "F.Fab")
		)
		(fp_line
			(start 0.504 -0.25)
			(end 0.504 0.248)
			(stroke
				(width 0.15)
				(type solid)
			)
			(layer "F.Fab")
		)
		(fp_text user "License: Apache-2.0"
			(at -0.939 5.799 90)
			(layer "F.Fab")
			(hide yes)
			(effects
				(font
					(size 0.7 0.7)
					(thickness 0.15)
				)
				(justify right bottom)
			)
		)
		(fp_text user "${REFERENCE}"
			(at -0.939 4.599 90)
			(layer "F.Fab")
			(hide yes)
			(effects
				(font
					(size 0.7 0.7)
					(thickness 0.15)
				)
				(justify right bottom)
			)
		)
		(fp_text user "Author: Antmicro"
			(at -0.939 3.399 90)
			(layer "F.Fab")
			(hide yes)
			(effects
				(font
					(size 0.7 0.7)
					(thickness 0.15)
				)
				(justify right bottom)
			)
		)
		(pad "1" smd roundrect
			(at -0.48 0 270)
			(size 0.59 0.64)
			(layers "F.Cu" "F.Paste" "F.Mask")
			(roundrect_rratio 0.25)
			(net 1 "GND")
			(pintype "passive")
		)
		(pad "2" smd roundrect
			(at 0.48 0 270)
			(size 0.59 0.64)
			(layers "F.Cu" "F.Paste" "F.Mask")
			(roundrect_rratio 0.25)
			(net 8 "/Supply/OUT_1V8")
			(pintype "passive")
		)
	)
)
